(kicad_pcb
	(version 20260206)
	(generator "pcbnew")
	(generator_version "10.0")
	(general
		(thickness 1.6)
		(legacy_teardrops no)
	)
	(paper "A4")
	(title_block
		(title "01162023_DA0F0TEBIF0_F0T_Expander_BD_F_brd_V02_OCP.brd")
		(comment 1 "Grand Teton / footprints 2154-2158 of 9728")
	)
	(layers
		(0 "F.Cu" signal "TOP")
		(4 "In1.Cu" signal "GND")
		(6 "In2.Cu" signal "VCC")
		(8 "In3.Cu" signal "VCC1")
		(10 "In4.Cu" signal "GND1")
		(12 "In5.Cu" signal "IN1")
		(14 "In6.Cu" signal "GND2")
		(16 "In7.Cu" signal "IN2")
		(18 "In8.Cu" signal "GND3")
		(20 "In9.Cu" signal "IN3")
		(22 "In10.Cu" signal "GND4")
		(24 "In11.Cu" signal "IN4")
		(26 "In12.Cu" signal "GND5")
		(28 "In13.Cu" signal "IN5")
		(30 "In14.Cu" signal "GND6")
		(32 "In15.Cu" signal "IN6")
		(34 "In16.Cu" signal "GND7")
		(2 "B.Cu" signal "BOTTOM")
		(9 "F.Adhes" user "F.Adhesive")
		(11 "B.Adhes" user "B.Adhesive")
		(13 "F.Paste" user "Package Geometry/Pastemask Top")
		(15 "B.Paste" user "Package Geometry/Pastemask Bottom")
		(5 "F.SilkS" user "Ref Des/Silkscreen Top")
		(7 "B.SilkS" user "Ref Des/Silkscreen Bottom")
		(1 "F.Mask" user "Board Geometry/Soldermask Top")
		(3 "B.Mask" user "Board Geometry/Soldermask Bottom")
		(17 "Dwgs.User" user "User.Drawings")
		(19 "Cmts.User" user "User.Comments")
		(21 "Eco1.User" user "User.Eco1")
		(23 "Eco2.User" user "User.Eco2")
		(25 "Edge.Cuts" user "Board Geometry/Outline")
		(27 "Margin" user)
		(31 "F.CrtYd" user "Package Geometry/Place Bound Top")
		(29 "B.CrtYd" user "Package Geometry/Place Bound Bottom")
		(35 "F.Fab" user "Ref Des/Assembly Top")
		(33 "B.Fab" user "Ref Des/Assembly Bottom")
	)
	(footprint ""
		(layer "F.Cu")
		(at 346.332302 -284.8991 180)
		(property "Reference" "PU13"
			(at -22.780498 -2.637536 90)
			(unlocked yes)
			(layer "F.SilkS")
			(effects
				(font
					(size 0.7874 0.5842)
					(thickness 0.1524)
				)
				(justify left)
			)
		)
		(property "Value" ""
			(at 0 0 180)
			(layer "F.Fab")
			(effects
				(font
					(size 1.27 1.27)
				)
			)
		)
		(duplicate_pad_numbers_are_jumpers no)
		(fp_line
			(start 2.500122 2.999994)
			(end 2.2987 2.999994)
			(stroke
				(width 0.1524)
				(type default)
			)
			(layer "F.SilkS")
		)
		(fp_line
			(start 2.500122 2.339594)
			(end 2.500122 2.999994)
			(stroke
				(width 0.1524)
				(type default)
			)
			(layer "F.SilkS")
		)
		(fp_line
			(start 2.500122 -2.999994)
			(end 2.500122 -2.44348)
			(stroke
				(width 0.1524)
				(type default)
			)
			(layer "F.SilkS")
		)
		(fp_line
			(start 2.31394 -2.999994)
			(end 2.500122 -2.999994)
			(stroke
				(width 0.1524)
				(type default)
			)
			(layer "F.SilkS")
		)
		(fp_line
			(start -2.2987 2.999994)
			(end -2.500122 2.999994)
			(stroke
				(width 0.1524)
				(type default)
			)
			(layer "F.SilkS")
		)
		(fp_line
			(start -2.500122 2.999994)
			(end -2.500122 2.339594)
			(stroke
				(width 0.1524)
				(type default)
			)
			(layer "F.SilkS")
		)
		(fp_line
			(start -2.500122 0.6604)
			(end -2.500122 0.229108)
			(stroke
				(width 0.1524)
				(type default)
			)
			(layer "F.SilkS")
		)
		(fp_line
			(start -2.500122 -2.529078)
			(end -2.500122 -2.999994)
			(stroke
				(width 0.1524)
				(type default)
			)
			(layer "F.SilkS")
		)
		(fp_line
			(start -2.500122 -2.999994)
			(end -2.24409 -2.999994)
			(stroke
				(width 0.1524)
				(type default)
			)
			(layer "F.SilkS")
		)
		(fp_poly
			(pts
				(xy -3.899916 -4.357116) (xy -4.618482 -3.63855) (xy -3.54076 -3.279394)
			)
			(stroke
				(width 0)
				(type default)
			)
			(fill yes)
			(layer "F.SilkS")
		)
		(fp_line
			(start 2.500122 2.999994)
			(end -2.500122 2.999994)
			(stroke
				(width 0.1)
				(type default)
			)
			(layer "F.Fab")
		)
		(fp_line
			(start 2.500122 -2.999994)
			(end 2.500122 2.999994)
			(stroke
				(width 0.1)
				(type default)
			)
			(layer "F.Fab")
		)
		(fp_line
			(start -2.500122 2.999994)
			(end -2.500122 -2.999994)
			(stroke
				(width 0.1)
				(type default)
			)
			(layer "F.Fab")
		)
		(fp_line
			(start -2.500122 -2.999994)
			(end 2.500122 -2.999994)
			(stroke
				(width 0.1)
				(type default)
			)
			(layer "F.Fab")
		)
		(fp_poly
			(pts
				(xy -4.218432 -2.783078) (xy -4.218432 -1.767078) (xy -3.202432 -2.275078)
			)
			(stroke
				(width 0)
				(type default)
			)
			(fill yes)
			(layer "F.Fab")
		)
		(pad "1" smd rect
			(at -2.400046 -2.275078 270)
			(size 0.2286 0.6096)
			(layers "F.Cu" "F.Mask" "F.Paste")
			(net "SW_P0V8_PEX2_VOS2")
		)
		(pad "2" smd rect
			(at -2.400046 -1.82499 270)
			(size 0.2286 0.6096)
			(layers "F.Cu" "F.Mask" "F.Paste")
			(net "GND")
		)
		(pad "3" smd rect
			(at -2.400046 -1.374902 270)
			(size 0.2286 0.6096)
			(layers "F.Cu" "F.Mask" "F.Paste")
			(net "P0V8_PEX2_VCC2")
		)
		(pad "4" smd rect
			(at -2.400046 -0.925068 270)
			(size 0.2286 0.6096)
			(layers "F.Cu" "F.Mask" "F.Paste")
			(net "P0V8_PEX2_PVCC")
		)
		(pad "5" smd rect
			(at -2.400046 -0.47498 270)
			(size 0.2286 0.6096)
			(layers "F.Cu" "F.Mask" "F.Paste")
			(net "GND")
		)
		(pad "6" smd rect
			(at -2.400046 -0.024892 270)
			(size 0.2286 0.6096)
			(layers "F.Cu" "F.Mask" "F.Paste")
			(net "NC_P0V8_PEX2_PH2_NC1")
		)
		(pad "7_9-20_24" smd circle
			(at 0 1.150112 270)
			(size 0 0)
			(layers "F.Cu" "F.Mask" "F.Paste")
			(net "GND")
		)
		(pad "10_19" smd rect
			(at 0 2.899918 270)
			(size 0.6096 4.318)
			(layers "F.Cu" "F.Mask" "F.Paste")
			(net "SW_P0V8_PEX2_PH2")
		)
		(pad "25_29" smd rect
			(at 1.549908 -1.279906 90)
			(size 2.0574 2.3114)
			(layers "F.Cu" "F.Mask" "F.Paste")
			(net "SW_P12V_P0V8_PEX2_FLT")
		)
		(pad "30" smd rect
			(at 2.05994 -2.899918 180)
			(size 0.2286 0.6096)
			(layers "F.Cu" "F.Mask" "F.Paste")
			(net "SW_P12V_P0V8_PEX2_FLT")
		)
		(pad "31" smd rect
			(at 1.610106 -2.899918 180)
			(size 0.2286 0.6096)
			(layers "F.Cu" "F.Mask" "F.Paste")
			(net "NC_P0V8_PEX2_PH2_NC3")
		)
		(pad "32" smd rect
			(at 1.160018 -2.899918 180)
			(size 0.2286 0.6096)
			(layers "F.Cu" "F.Mask" "F.Paste")
			(net "SW_P0V8_PEX2_PHASE2")
		)
		(pad "33" smd rect
			(at 0.70993 -2.899918 180)
			(size 0.2286 0.6096)
			(layers "F.Cu" "F.Mask" "F.Paste")
			(net "SW_P0V8_PEX2_BOOT2")
		)
		(pad "34" smd rect
			(at 0.260096 -2.899918 180)
			(size 0.2286 0.6096)
			(layers "F.Cu" "F.Mask" "F.Paste")
			(net "P0V8_PEX2_PWM2")
		)
		(pad "35" smd rect
			(at -0.189992 -2.899918 180)
			(size 0.2286 0.6096)
			(layers "F.Cu" "F.Mask" "F.Paste")
			(net "P0V8_PEX2_EN2")
		)
		(pad "36" smd rect
			(at -0.64008 -2.899918 180)
			(size 0.2286 0.6096)
			(layers "F.Cu" "F.Mask" "F.Paste")
			(net "P0V8_PEX2_TSEN")
		)
		(pad "37" smd rect
			(at -1.089914 -2.899918 180)
			(size 0.2286 0.6096)
			(layers "F.Cu" "F.Mask" "F.Paste")
			(net "P0V8_PEX2_LSET2")
		)
		(pad "38" smd rect
			(at -1.540002 -2.899918 180)
			(size 0.2286 0.6096)
			(layers "F.Cu" "F.Mask" "F.Paste")
			(net "P0V8_PEX2_ISEN2")
		)
		(pad "39" smd rect
			(at -1.99009 -2.899918 180)
			(size 0.2286 0.6096)
			(layers "F.Cu" "F.Mask" "F.Paste")
			(net "P0V8_PEX2_VREF")
		)
		(pad "40" smd rect
			(at -0.87503 -1.27508 180)
			(size 1.7526 1.9558)
			(layers "F.Cu" "F.Mask" "F.Paste")
			(net "GND")
		)
		(pad "41" smd rect
			(at -1.525016 0.249936 90)
			(size 0.3048 0.4572)
			(layers "F.Cu" "F.Mask" "F.Paste")
			(net "NC_P0V8_PEX2_PH2_NC2")
		)
		(zone
			(layer "F.Cu")
			(hatch none 0.5)
			(connect_pads
				(clearance 0)
			)
			(min_thickness 0.25)
			(keepout
				(tracks not_allowed)
				(vias allowed)
				(pads allowed)
				(copperpour not_allowed)
				(footprints allowed)
			)
			(placement
				(enabled no)
				(sheetname "")
			)
			(fill
				(thermal_gap 0.5)
				(thermal_bridge_width 0.5)
				(island_removal_mode 0)
			)
			(polygon
				(pts
					(xy 348.832424 -287.899094) (xy 348.832424 -287.149794) (xy 343.83218 -287.149794) (xy 343.83218 -287.899094)
					(xy 344.122502 -287.899094) (xy 344.122502 -287.443418) (xy 348.542102 -287.443418) (xy 348.542102 -287.899094)
				)
			)
		)
	)
	(footprint ""
		(layer "F.Cu")
		(at 458.101446 -250.20524 180)
		(property "Reference" "R6588"
			(at 0 0 180)
			(layer "F.SilkS")
			(hide yes)
			(effects
				(font
					(size 1.27 1.27)
				)
			)
		)
		(property "Value" ""
			(at 0 0 180)
			(layer "F.Fab")
			(effects
				(font
					(size 1.27 1.27)
				)
			)
		)
		(duplicate_pad_numbers_are_jumpers no)
		(fp_line
			(start 0.7874 0.4064)
			(end -0.7874 0.4064)
			(stroke
				(width 0.1524)
				(type default)
			)
			(layer "F.SilkS")
		)
		(fp_line
			(start 0.7874 -0.4064)
			(end 0.7874 0.4064)
			(stroke
				(width 0.1524)
				(type default)
			)
			(layer "F.SilkS")
		)
		(fp_line
			(start -0.7874 0.4064)
			(end -0.7874 -0.4064)
			(stroke
				(width 0.1524)
				(type default)
			)
			(layer "F.SilkS")
		)
		(fp_line
			(start -0.7874 -0.4064)
			(end 0.7874 -0.4064)
			(stroke
				(width 0.1524)
				(type default)
			)
			(layer "F.SilkS")
		)
		(fp_line
			(start 0.67945 0.3048)
			(end 0.120396 0.3048)
			(stroke
				(width 0.1)
				(type default)
			)
			(layer "F.Fab")
		)
		(fp_line
			(start 0.67945 -0.3048)
			(end 0.67945 0.3048)
			(stroke
				(width 0.1)
				(type default)
			)
			(layer "F.Fab")
		)
		(fp_line
			(start 0.12065 -0.2794)
			(end 0.12065 -0.3048)
			(stroke
				(width 0.1)
				(type default)
			)
			(layer "F.Fab")
		)
		(fp_line
			(start 0.12065 -0.3048)
			(end 0.67945 -0.3048)
			(stroke
				(width 0.1)
				(type default)
			)
			(layer "F.Fab")
		)
		(fp_line
			(start 0.120396 0.3048)
			(end 0.120396 0.2794)
			(stroke
				(width 0.1)
				(type default)
			)
			(layer "F.Fab")
		)
		(fp_line
			(start 0.120396 0.2794)
			(end -0.12065 0.2794)
			(stroke
				(width 0.1)
				(type default)
			)
			(layer "F.Fab")
		)
		(fp_line
			(start -0.12065 0.3048)
			(end -0.67945 0.3048)
			(stroke
				(width 0.1)
				(type default)
			)
			(layer "F.Fab")
		)
		(fp_line
			(start -0.12065 0.2794)
			(end -0.12065 0.3048)
			(stroke
				(width 0.1)
				(type default)
			)
			(layer "F.Fab")
		)
		(fp_line
			(start -0.12065 -0.2794)
			(end 0.12065 -0.2794)
			(stroke
				(width 0.1)
				(type default)
			)
			(layer "F.Fab")
		)
		(fp_line
			(start -0.12065 -0.305054)
			(end -0.12065 -0.2794)
			(stroke
				(width 0.1)
				(type default)
			)
			(layer "F.Fab")
		)
		(fp_line
			(start -0.67945 0.3048)
			(end -0.67945 -0.305054)
			(stroke
				(width 0.1)
				(type default)
			)
			(layer "F.Fab")
		)
		(fp_line
			(start -0.67945 -0.305054)
			(end -0.12065 -0.305054)
			(stroke
				(width 0.1)
				(type default)
			)
			(layer "F.Fab")
		)
		(pad "1" smd circle
			(at -0.40005 0 180)
			(size 0 0)
			(layers "F.Cu" "F.Mask" "F.Paste")
			(net "PWRGD_PEX3_P1V8_PLL_R")
		)
		(pad "2" smd circle
			(at 0.40005 0 180)
			(size 0 0)
			(layers "F.Cu" "F.Mask" "F.Paste")
			(net "PWRGD_PEX3_P1V8_PLL")
		)
	)
	(footprint ""
		(layer "F.Cu")
		(at 129.13487 -279.101804)
		(property "Reference" "PC108"
			(at 0 0 0)
			(layer "F.SilkS")
			(hide yes)
			(effects
				(font
					(size 1.27 1.27)
				)
			)
		)
		(property "Value" ""
			(at 0 0 0)
			(layer "F.Fab")
			(effects
				(font
					(size 1.27 1.27)
				)
			)
		)
		(duplicate_pad_numbers_are_jumpers no)
		(fp_line
			(start -0.7874 -0.4064)
			(end 0.7874 -0.4064)
			(stroke
				(width 0.1524)
				(type default)
			)
			(layer "F.SilkS")
		)
		(fp_line
			(start -0.7874 0.4064)
			(end -0.7874 -0.4064)
			(stroke
				(width 0.1524)
				(type default)
			)
			(layer "F.SilkS")
		)
		(fp_line
			(start 0.7874 -0.4064)
			(end 0.7874 0.4064)
			(stroke
				(width 0.1524)
				(type default)
			)
			(layer "F.SilkS")
		)
		(fp_line
			(start 0.7874 0.4064)
			(end -0.7874 0.4064)
			(stroke
				(width 0.1524)
				(type default)
			)
			(layer "F.SilkS")
		)
		(fp_line
			(start -0.67945 -0.305054)
			(end -0.12065 -0.305054)
			(stroke
				(width 0.1)
				(type default)
			)
			(layer "F.Fab")
		)
		(fp_line
			(start -0.67945 0.3048)
			(end -0.67945 -0.305054)
			(stroke
				(width 0.1)
				(type default)
			)
			(layer "F.Fab")
		)
		(fp_line
			(start -0.12065 -0.305054)
			(end -0.12065 -0.2794)
			(stroke
				(width 0.1)
				(type default)
			)
			(layer "F.Fab")
		)
		(fp_line
			(start -0.12065 -0.2794)
			(end 0.12065 -0.2794)
			(stroke
				(width 0.1)
				(type default)
			)
			(layer "F.Fab")
		)
		(fp_line
			(start -0.12065 0.2794)
			(end -0.12065 0.3048)
			(stroke
				(width 0.1)
				(type default)
			)
			(layer "F.Fab")
		)
		(fp_line
			(start -0.12065 0.3048)
			(end -0.67945 0.3048)
			(stroke
				(width 0.1)
				(type default)
			)
			(layer "F.Fab")
		)
		(fp_line
			(start 0.120396 0.2794)
			(end -0.12065 0.2794)
			(stroke
				(width 0.1)
				(type default)
			)
			(layer "F.Fab")
		)
		(fp_line
			(start 0.120396 0.3048)
			(end 0.120396 0.2794)
			(stroke
				(width 0.1)
				(type default)
			)
			(layer "F.Fab")
		)
		(fp_line
			(start 0.12065 -0.3048)
			(end 0.67945 -0.3048)
			(stroke
				(width 0.1)
				(type default)
			)
			(layer "F.Fab")
		)
		(fp_line
			(start 0.12065 -0.2794)
			(end 0.12065 -0.3048)
			(stroke
				(width 0.1)
				(type default)
			)
			(layer "F.Fab")
		)
		(fp_line
			(start 0.67945 -0.3048)
			(end 0.67945 0.3048)
			(stroke
				(width 0.1)
				(type default)
			)
			(layer "F.Fab")
		)
		(fp_line
			(start 0.67945 0.3048)
			(end 0.120396 0.3048)
			(stroke
				(width 0.1)
				(type default)
			)
			(layer "F.Fab")
		)
		(pad "1" smd circle
			(at -0.40005 0)
			(size 0 0)
			(layers "F.Cu" "F.Mask" "F.Paste")
			(net "SW_P12V_P0V8_PEX1_FLT")
		)
		(pad "2" smd circle
			(at 0.40005 0)
			(size 0 0)
			(layers "F.Cu" "F.Mask" "F.Paste")
			(net "GND")
		)
	)
	(footprint ""
		(layer "F.Cu")
		(at 427.923452 -350.098614 90)
		(property "Reference" "C2457"
			(at 0 0 90)
			(layer "F.SilkS")
			(hide yes)
			(effects
				(font
					(size 1.27 1.27)
				)
			)
		)
		(property "Value" ""
			(at 0 0 90)
			(layer "F.Fab")
			(effects
				(font
					(size 1.27 1.27)
				)
			)
		)
		(duplicate_pad_numbers_are_jumpers no)
		(fp_line
			(start 0.299974 -0.150114)
			(end 0.299974 0.150114)
			(stroke
				(width 0.1)
				(type default)
			)
			(layer "F.Fab")
		)
		(fp_line
			(start -0.299974 -0.150114)
			(end 0.299974 -0.150114)
			(stroke
				(width 0.1)
				(type default)
			)
			(layer "F.Fab")
		)
		(fp_line
			(start 0.299974 0.150114)
			(end -0.299974 0.150114)
			(stroke
				(width 0.1)
				(type default)
			)
			(layer "F.Fab")
		)
		(fp_line
			(start -0.299974 0.150114)
			(end -0.299974 -0.150114)
			(stroke
				(width 0.1)
				(type default)
			)
			(layer "F.Fab")
		)
		(pad "1" smd rect
			(at -0.2667 0 90)
			(size 0.3048 0.381)
			(layers "F.Cu" "F.Mask" "F.Paste")
			(net "P5E_PEX3_STN4_TX_DP<70>")
		)
		(pad "2" smd rect
			(at 0.2667 0 90)
			(size 0.3048 0.381)
			(layers "F.Cu" "F.Mask" "F.Paste")
			(net "P5E_PEX3_STN4_TX_C_DP<70>")
		)
	)
	(footprint ""
		(layer "F.Cu")
		(at 5.684774 -393.744958 -90)
		(property "Reference" "R6753"
			(at 0 0 270)
			(layer "F.SilkS")
			(hide yes)
			(effects
				(font
					(size 1.27 1.27)
				)
			)
		)
		(property "Value" ""
			(at 0 0 270)
			(layer "F.Fab")
			(effects
				(font
					(size 1.27 1.27)
				)
			)
		)
		(duplicate_pad_numbers_are_jumpers no)
		(fp_line
			(start -0.7874 0.4064)
			(end -0.7874 -0.4064)
			(stroke
				(width 0.1524)
				(type default)
			)
			(layer "F.SilkS")
		)
		(fp_line
			(start 0.7874 0.4064)
			(end -0.7874 0.4064)
			(stroke
				(width 0.1524)
				(type default)
			)
			(layer "F.SilkS")
		)
		(fp_line
			(start -0.7874 -0.4064)
			(end 0.7874 -0.4064)
			(stroke
				(width 0.1524)
				(type default)
			)
			(layer "F.SilkS")
		)
		(fp_line
			(start 0.7874 -0.4064)
			(end 0.7874 0.4064)
			(stroke
				(width 0.1524)
				(type default)
			)
			(layer "F.SilkS")
		)
		(fp_line
			(start -0.67945 0.3048)
			(end -0.67945 -0.305054)
			(stroke
				(width 0.1)
				(type default)
			)
			(layer "F.Fab")
		)
		(fp_line
			(start -0.12065 0.3048)
			(end -0.67945 0.3048)
			(stroke
				(width 0.1)
				(type default)
			)
			(layer "F.Fab")
		)
		(fp_line
			(start 0.120396 0.3048)
			(end 0.120396 0.2794)
			(stroke
				(width 0.1)
				(type default)
			)
			(layer "F.Fab")
		)
		(fp_line
			(start 0.67945 0.3048)
			(end 0.120396 0.3048)
			(stroke
				(width 0.1)
				(type default)
			)
			(layer "F.Fab")
		)
		(fp_line
			(start -0.12065 0.2794)
			(end -0.12065 0.3048)
			(stroke
				(width 0.1)
				(type default)
			)
			(layer "F.Fab")
		)
		(fp_line
			(start 0.120396 0.2794)
			(end -0.12065 0.2794)
			(stroke
				(width 0.1)
				(type default)
			)
			(layer "F.Fab")
		)
		(fp_line
			(start -0.12065 -0.2794)
			(end 0.12065 -0.2794)
			(stroke
				(width 0.1)
				(type default)
			)
			(layer "F.Fab")
		)
		(fp_line
			(start 0.12065 -0.2794)
			(end 0.12065 -0.3048)
			(stroke
				(width 0.1)
				(type default)
			)
			(layer "F.Fab")
		)
		(fp_line
			(start 0.12065 -0.3048)
			(end 0.67945 -0.3048)
			(stroke
				(width 0.1)
				(type default)
			)
			(layer "F.Fab")
		)
		(fp_line
			(start 0.67945 -0.3048)
			(end 0.67945 0.3048)
			(stroke
				(width 0.1)
				(type default)
			)
			(layer "F.Fab")
		)
		(fp_line
			(start -0.67945 -0.305054)
			(end -0.12065 -0.305054)
			(stroke
				(width 0.1)
				(type default)
			)
			(layer "F.Fab")
		)
		(fp_line
			(start -0.12065 -0.305054)
			(end -0.12065 -0.2794)
			(stroke
				(width 0.1)
				(type default)
			)
			(layer "F.Fab")
		)
		(pad "1" smd circle
			(at -0.40005 0 270)
			(size 0 0)
			(layers "F.Cu" "F.Mask" "F.Paste")
			(net "P5V_AUX")
		)
		(pad "2" smd circle
			(at 0.40005 0 270)
			(size 0 0)
			(layers "F.Cu" "F.Mask" "F.Paste")
			(net "BIC_USB_8042_HUB_VBUS")
		)
	)
)
